FILE_TYPE = MACRO_DRAWING;
SET COLOR_WIRE YELLOW;
SET COLOR_PROP MONO;
SET COLOR_DOT WHITE;
SET COLOR_ARC YELLOW;
SET COLOR_BODY GREEN;
SET COLOR_NOTE MONO;
SET PROP_DISPLAY VALUE;
SET PAGE_NUMBER P123;
FORCEADD LBG_CORE_QAT_EXT_D..11
(-1625 2575);
FORCEPROP 1 LAST LOCATION U7C1
J 0
(-2175 4525);
DISPLAY 0.617021 (-2175 4525);
PAINT AQUA (-2175 4525);
FORCEPROP 1 LAST PART_NUMBER H91415-002
J 0
(-2175 625);
DISPLAY 0.617021 (-2175 625);
PAINT BLUE (-2175 625);
FORCEPROP 1 LAST MATERIAL IC
J 0
(-2175 4475);
DISPLAY 0.617021 (-2175 4475);
PAINT SKYBLUE (-2175 4475);
FORCEPROP 2 LASTPIN (-1025 825) $PN N31
J 0
(-1015 835);
DISPLAY 0.617021 (-1015 835);
PAINT ORANGE (-1015 835);
FORCEPROP 2 LASTPIN (-1025 875) $PN N27
J 0
(-1015 885);
DISPLAY 0.617021 (-1015 885);
PAINT ORANGE (-1015 885);
FORCEPROP 2 LASTPIN (-1025 925) $PN N24
J 0
(-1015 935);
DISPLAY 0.617021 (-1015 935);
PAINT ORANGE (-1015 935);
FORCEPROP 2 LASTPIN (-1025 975) $PN N20
J 0
(-1015 985);
DISPLAY 0.617021 (-1015 985);
PAINT ORANGE (-1015 985);
FORCEPROP 2 LASTPIN (-1025 1025) $PN N17
J 0
(-1015 1035);
DISPLAY 0.617021 (-1015 1035);
PAINT ORANGE (-1015 1035);
FORCEPROP 2 LASTPIN (-1025 1075) $PN N13
J 0
(-1015 1085);
DISPLAY 0.617021 (-1015 1085);
PAINT ORANGE (-1015 1085);
FORCEPROP 2 LASTPIN (-1025 1125) $PN M48
J 0
(-1015 1135);
DISPLAY 0.617021 (-1015 1135);
PAINT ORANGE (-1015 1135);
FORCEPROP 2 LASTPIN (-1025 1175) $PN M44
J 0
(-1015 1185);
DISPLAY 0.617021 (-1015 1185);
PAINT ORANGE (-1015 1185);
FORCEPROP 2 LASTPIN (-1025 1225) $PN N50
J 0
(-1015 1235);
DISPLAY 0.617021 (-1015 1235);
PAINT ORANGE (-1015 1235);
FORCEPROP 2 LASTPIN (-1025 1275) $PN N42
J 0
(-1015 1285);
DISPLAY 0.617021 (-1015 1285);
PAINT ORANGE (-1015 1285);
FORCEPROP 2 LASTPIN (-1025 1325) $PN M40
J 0
(-1015 1335);
DISPLAY 0.617021 (-1015 1335);
PAINT ORANGE (-1015 1335);
FORCEPROP 2 LASTPIN (-1025 1375) $PN M4
J 0
(-1015 1385);
DISPLAY 0.617021 (-1015 1385);
PAINT ORANGE (-1015 1385);
FORCEPROP 2 LASTPIN (-1025 1425) $PN M37
J 0
(-1015 1435);
DISPLAY 0.617021 (-1015 1435);
PAINT ORANGE (-1015 1435);
FORCEPROP 2 LASTPIN (-1025 1475) $PN M33
J 0
(-1015 1485);
DISPLAY 0.617021 (-1015 1485);
PAINT ORANGE (-1015 1485);
FORCEPROP 2 LASTPIN (-1025 1525) $PN M29
J 0
(-1015 1535);
DISPLAY 0.617021 (-1015 1535);
PAINT ORANGE (-1015 1535);
FORCEPROP 2 LASTPIN (-1025 1575) $PN M26
J 0
(-1015 1585);
DISPLAY 0.617021 (-1015 1585);
PAINT ORANGE (-1015 1585);
FORCEPROP 2 LASTPIN (-1025 1625) $PN M22
J 0
(-1015 1635);
DISPLAY 0.617021 (-1015 1635);
PAINT ORANGE (-1015 1635);
FORCEPROP 2 LASTPIN (-1025 1675) $PN M2
J 0
(-1015 1685);
DISPLAY 0.617021 (-1015 1685);
PAINT ORANGE (-1015 1685);
FORCEPROP 2 LASTPIN (-1025 1725) $PN L68
J 0
(-1015 1735);
DISPLAY 0.617021 (-1015 1735);
PAINT ORANGE (-1015 1735);
FORCEPROP 2 LASTPIN (-1025 1775) $PN L5
J 0
(-1015 1785);
DISPLAY 0.617021 (-1015 1785);
PAINT ORANGE (-1015 1785);
FORCEPROP 2 LASTPIN (-1025 1825) $PN K71
J 0
(-1015 1835);
DISPLAY 0.617021 (-1015 1835);
PAINT ORANGE (-1015 1835);
FORCEPROP 2 LASTPIN (-1025 1875) $PN K69
J 0
(-1015 1885);
DISPLAY 0.617021 (-1015 1885);
PAINT ORANGE (-1015 1885);
FORCEPROP 2 LASTPIN (-1025 1925) $PN K54
J 0
(-1015 1935);
DISPLAY 0.617021 (-1015 1935);
PAINT ORANGE (-1015 1935);
FORCEPROP 2 LASTPIN (-1025 1975) $PN J70
J 0
(-1015 1985);
DISPLAY 0.617021 (-1015 1985);
PAINT ORANGE (-1015 1985);
FORCEPROP 2 LASTPIN (-1025 2025) $PN J68
J 0
(-1015 2035);
DISPLAY 0.617021 (-1015 2035);
PAINT ORANGE (-1015 2035);
FORCEPROP 2 LASTPIN (-1025 2075) $PN J59
J 0
(-1015 2085);
DISPLAY 0.617021 (-1015 2085);
PAINT ORANGE (-1015 2085);
FORCEPROP 2 LASTPIN (-1025 2125) $PN J44
J 0
(-1015 2135);
DISPLAY 0.617021 (-1015 2135);
PAINT ORANGE (-1015 2135);
FORCEPROP 2 LASTPIN (-1025 2175) $PN J37
J 0
(-1015 2185);
DISPLAY 0.617021 (-1015 2185);
PAINT ORANGE (-1015 2185);
FORCEPROP 2 LASTPIN (-1025 2225) $PN J22
J 0
(-1015 2235);
DISPLAY 0.617021 (-1015 2235);
PAINT ORANGE (-1015 2235);
FORCEPROP 2 LASTPIN (-1025 2275) $PN J15
J 0
(-1015 2285);
DISPLAY 0.617021 (-1015 2285);
PAINT ORANGE (-1015 2285);
FORCEPROP 2 LASTPIN (-1025 2325) $PN J11
J 0
(-1015 2335);
DISPLAY 0.617021 (-1015 2335);
PAINT ORANGE (-1015 2335);
FORCEPROP 2 LASTPIN (-1025 2375) $PN H65
J 0
(-1015 2385);
DISPLAY 0.617021 (-1015 2385);
PAINT ORANGE (-1015 2385);
FORCEPROP 2 LASTPIN (-1025 2425) $PN J7
J 0
(-1015 2435);
DISPLAY 0.617021 (-1015 2435);
PAINT ORANGE (-1015 2435);
FORCEPROP 2 LASTPIN (-1025 2475) $PN J5
J 0
(-1015 2485);
DISPLAY 0.617021 (-1015 2485);
PAINT ORANGE (-1015 2485);
FORCEPROP 2 LASTPIN (-1025 2525) $PN J29
J 0
(-1015 2535);
DISPLAY 0.617021 (-1015 2535);
PAINT ORANGE (-1015 2535);
FORCEPROP 2 LASTPIN (-1025 2575) $PN H58
J 0
(-1015 2585);
DISPLAY 0.617021 (-1015 2585);
PAINT ORANGE (-1015 2585);
FORCEPROP 2 LASTPIN (-1025 2625) $PN G66
J 0
(-1015 2635);
DISPLAY 0.617021 (-1015 2635);
PAINT ORANGE (-1015 2635);
FORCEPROP 2 LASTPIN (-1025 2675) $PN G63
J 0
(-1015 2685);
DISPLAY 0.617021 (-1015 2685);
PAINT ORANGE (-1015 2685);
FORCEPROP 2 LASTPIN (-1025 2725) $PN G6
J 0
(-1015 2735);
DISPLAY 0.617021 (-1015 2735);
PAINT ORANGE (-1015 2735);
FORCEPROP 2 LASTPIN (-1025 2775) $PN G48
J 0
(-1015 2785);
DISPLAY 0.617021 (-1015 2785);
PAINT ORANGE (-1015 2785);
FORCEPROP 2 LASTPIN (-1025 2825) $PN G37
J 0
(-1015 2835);
DISPLAY 0.617021 (-1015 2835);
PAINT ORANGE (-1015 2835);
FORCEPROP 2 LASTPIN (-1025 2875) $PN G29
J 0
(-1015 2885);
DISPLAY 0.617021 (-1015 2885);
PAINT ORANGE (-1015 2885);
FORCEPROP 2 LASTPIN (-1025 2925) $PN G22
J 0
(-1015 2935);
DISPLAY 0.617021 (-1015 2935);
PAINT ORANGE (-1015 2935);
FORCEPROP 2 LASTPIN (-1025 2975) $PN E9
J 0
(-1015 2985);
DISPLAY 0.617021 (-1015 2985);
PAINT ORANGE (-1015 2985);
FORCEPROP 2 LASTPIN (-1025 3025) $PN G59
J 0
(-1015 3035);
DISPLAY 0.617021 (-1015 3035);
PAINT ORANGE (-1015 3035);
FORCEPROP 2 LASTPIN (-1025 3075) $PN E63
J 0
(-1015 3085);
DISPLAY 0.617021 (-1015 3085);
PAINT ORANGE (-1015 3085);
FORCEPROP 2 LASTPIN (-1025 3125) $PN E61
J 0
(-1015 3135);
DISPLAY 0.617021 (-1015 3135);
PAINT ORANGE (-1015 3135);
FORCEPROP 2 LASTPIN (-1025 3175) $PN E6
J 0
(-1015 3185);
DISPLAY 0.617021 (-1015 3185);
PAINT ORANGE (-1015 3185);
FORCEPROP 2 LASTPIN (-1025 3225) $PN E57
J 0
(-1015 3235);
DISPLAY 0.617021 (-1015 3235);
PAINT ORANGE (-1015 3235);
FORCEPROP 2 LASTPIN (-1025 3275) $PN E54
J 0
(-1015 3285);
DISPLAY 0.617021 (-1015 3285);
PAINT ORANGE (-1015 3285);
FORCEPROP 2 LASTPIN (-1025 3325) $PN E52
J 0
(-1015 3335);
DISPLAY 0.617021 (-1015 3335);
PAINT ORANGE (-1015 3335);
FORCEPROP 2 LASTPIN (-1025 3375) $PN E50
J 0
(-1015 3385);
DISPLAY 0.617021 (-1015 3385);
PAINT ORANGE (-1015 3385);
FORCEPROP 2 LASTPIN (-1025 3425) $PN E48
J 0
(-1015 3435);
DISPLAY 0.617021 (-1015 3435);
PAINT ORANGE (-1015 3435);
FORCEPROP 2 LASTPIN (-1025 3475) $PN E45
J 0
(-1015 3485);
DISPLAY 0.617021 (-1015 3485);
PAINT ORANGE (-1015 3485);
FORCEPROP 2 LASTPIN (-1025 3525) $PN E43
J 0
(-1015 3535);
DISPLAY 0.617021 (-1015 3535);
PAINT ORANGE (-1015 3535);
FORCEPROP 2 LASTPIN (-1025 3575) $PN E41
J 0
(-1015 3585);
DISPLAY 0.617021 (-1015 3585);
PAINT ORANGE (-1015 3585);
FORCEPROP 2 LASTPIN (-1025 3625) $PN E39
J 0
(-1015 3635);
DISPLAY 0.617021 (-1015 3635);
PAINT ORANGE (-1015 3635);
FORCEPROP 2 LASTPIN (-1025 3675) $PN E37
J 0
(-1015 3685);
DISPLAY 0.617021 (-1015 3685);
PAINT ORANGE (-1015 3685);
FORCEPROP 2 LASTPIN (-1025 3725) $PN E34
J 0
(-1015 3735);
DISPLAY 0.617021 (-1015 3735);
PAINT ORANGE (-1015 3735);
FORCEPROP 2 LASTPIN (-1025 3775) $PN E32
J 0
(-1015 3785);
DISPLAY 0.617021 (-1015 3785);
PAINT ORANGE (-1015 3785);
FORCEPROP 2 LASTPIN (-1025 3825) $PN E30
J 0
(-1015 3835);
DISPLAY 0.617021 (-1015 3835);
PAINT ORANGE (-1015 3835);
FORCEPROP 2 LASTPIN (-1025 3875) $PN E28
J 0
(-1015 3885);
DISPLAY 0.617021 (-1015 3885);
PAINT ORANGE (-1015 3885);
FORCEPROP 2 LASTPIN (-1025 3925) $PN E26
J 0
(-1015 3935);
DISPLAY 0.617021 (-1015 3935);
PAINT ORANGE (-1015 3935);
FORCEPROP 2 LASTPIN (-1025 3975) $PN E24
J 0
(-1015 3985);
DISPLAY 0.617021 (-1015 3985);
PAINT ORANGE (-1015 3985);
FORCEPROP 2 LASTPIN (-1025 4025) $PN E22
J 0
(-1015 4035);
DISPLAY 0.617021 (-1015 4035);
PAINT ORANGE (-1015 4035);
FORCEPROP 2 LASTPIN (-1025 4075) $PN E20
J 0
(-1015 4085);
DISPLAY 0.617021 (-1015 4085);
PAINT ORANGE (-1015 4085);
FORCEPROP 2 LASTPIN (-1025 4125) $PN E15
J 0
(-1015 4135);
DISPLAY 0.617021 (-1015 4135);
PAINT ORANGE (-1015 4135);
FORCEPROP 2 LASTPIN (-1025 4175) $PN E13
J 0
(-1015 4185);
DISPLAY 0.617021 (-1015 4185);
PAINT ORANGE (-1015 4185);
FORCEPROP 2 LASTPIN (-1025 4225) $PN E11
J 0
(-1015 4235);
DISPLAY 0.617021 (-1015 4235);
PAINT ORANGE (-1015 4235);
FORCEPROP 2 LASTPIN (-1025 4275) $PN D47
J 0
(-1015 4285);
DISPLAY 0.617021 (-1015 4285);
PAINT ORANGE (-1015 4285);
FORCEPROP 2 LASTPIN (-2225 825) $PN E65
J 2
(-2235 835);
DISPLAY 0.617021 (-2235 835);
PAINT ORANGE (-2235 835);
FORCEPROP 2 LASTPIN (-2225 875) $PN E59
J 2
(-2235 885);
DISPLAY 0.617021 (-2235 885);
PAINT ORANGE (-2235 885);
FORCEPROP 2 LASTPIN (-2225 925) $PN D27
J 2
(-2235 935);
DISPLAY 0.617021 (-2235 935);
PAINT ORANGE (-2235 935);
FORCEPROP 2 LASTPIN (-2225 975) $PN D25
J 2
(-2235 985);
DISPLAY 0.617021 (-2235 985);
PAINT ORANGE (-2235 985);
FORCEPROP 2 LASTPIN (-2225 1025) $PN D19
J 2
(-2235 1035);
DISPLAY 0.617021 (-2235 1035);
PAINT ORANGE (-2235 1035);
FORCEPROP 2 LASTPIN (-2225 1075) $PN D16
J 2
(-2235 1085);
DISPLAY 0.617021 (-2235 1085);
PAINT ORANGE (-2235 1085);
FORCEPROP 2 LASTPIN (-2225 1125) $PN D12
J 2
(-2235 1135);
DISPLAY 0.617021 (-2235 1135);
PAINT ORANGE (-2235 1135);
FORCEPROP 2 LASTPIN (-2225 1175) $PN C65
J 2
(-2235 1185);
DISPLAY 0.617021 (-2235 1185);
PAINT ORANGE (-2235 1185);
FORCEPROP 2 LASTPIN (-2225 1225) $PN C41
J 2
(-2235 1235);
DISPLAY 0.617021 (-2235 1235);
PAINT ORANGE (-2235 1235);
FORCEPROP 2 LASTPIN (-2225 1275) $PN C37
J 2
(-2235 1285);
DISPLAY 0.617021 (-2235 1285);
PAINT ORANGE (-2235 1285);
FORCEPROP 2 LASTPIN (-2225 1325) $PN C34
J 2
(-2235 1335);
DISPLAY 0.617021 (-2235 1335);
PAINT ORANGE (-2235 1335);
FORCEPROP 2 LASTPIN (-2225 1375) $PN C30
J 2
(-2235 1385);
DISPLAY 0.617021 (-2235 1385);
PAINT ORANGE (-2235 1385);
FORCEPROP 2 LASTPIN (-2225 1425) $PN C22
J 2
(-2235 1435);
DISPLAY 0.617021 (-2235 1435);
PAINT ORANGE (-2235 1435);
FORCEPROP 2 LASTPIN (-2225 1475) $PN B47
J 2
(-2235 1485);
DISPLAY 0.617021 (-2235 1485);
PAINT ORANGE (-2235 1485);
FORCEPROP 2 LASTPIN (-2225 1525) $PN B27
J 2
(-2235 1535);
DISPLAY 0.617021 (-2235 1535);
PAINT ORANGE (-2235 1535);
FORCEPROP 2 LASTPIN (-2225 1575) $PN B25
J 2
(-2235 1585);
DISPLAY 0.617021 (-2235 1585);
PAINT ORANGE (-2235 1585);
FORCEPROP 2 LASTPIN (-2225 1625) $PN B19
J 2
(-2235 1635);
DISPLAY 0.617021 (-2235 1635);
PAINT ORANGE (-2235 1635);
FORCEPROP 2 LASTPIN (-2225 1675) $PN B12
J 2
(-2235 1685);
DISPLAY 0.617021 (-2235 1685);
PAINT ORANGE (-2235 1685);
FORCEPROP 2 LASTPIN (-2225 1775) $PN A37
J 2
(-2235 1785);
DISPLAY 0.617021 (-2235 1785);
PAINT ORANGE (-2235 1785);
FORCEPROP 2 LASTPIN (-2225 1825) $PN A34
J 2
(-2235 1835);
DISPLAY 0.617021 (-2235 1835);
PAINT ORANGE (-2235 1835);
FORCEPROP 2 LASTPIN (-2225 1875) $PN A30
J 2
(-2235 1885);
DISPLAY 0.617021 (-2235 1885);
PAINT ORANGE (-2235 1885);
FORCEPROP 2 LASTPIN (-2225 1925) $PN A22
J 2
(-2235 1935);
DISPLAY 0.617021 (-2235 1935);
PAINT ORANGE (-2235 1935);
FORCEPROP 2 LASTPIN (-2225 1975) $PN A18
J 2
(-2235 1985);
DISPLAY 0.617021 (-2235 1985);
PAINT ORANGE (-2235 1985);
FORCEPROP 2 LASTPIN (-2225 2025) $PN Y70
J 2
(-2235 2035);
DISPLAY 0.617021 (-2235 2035);
PAINT ORANGE (-2235 2035);
FORCEPROP 2 LASTPIN (-2225 2075) $PN Y72
J 2
(-2235 2085);
DISPLAY 0.617021 (-2235 2085);
PAINT ORANGE (-2235 2085);
FORCEPROP 2 LASTPIN (-2225 2125) $PN AT37
J 2
(-2235 2135);
DISPLAY 0.617021 (-2235 2135);
PAINT ORANGE (-2235 2135);
FORCEPROP 2 LASTPIN (-2225 2175) $PN BB48
J 2
(-2235 2185);
DISPLAY 0.617021 (-2235 2185);
PAINT ORANGE (-2235 2185);
FORCEPROP 2 LASTPIN (-2225 2225) $PN CA70
J 2
(-2235 2235);
DISPLAY 0.617021 (-2235 2235);
PAINT ORANGE (-2235 2235);
FORCEPROP 2 LASTPIN (-2225 2275) $PN BW72
J 2
(-2235 2285);
DISPLAY 0.617021 (-2235 2285);
PAINT ORANGE (-2235 2285);
FORCEPROP 2 LASTPIN (-2225 2325) $PN BW70
J 2
(-2235 2335);
DISPLAY 0.617021 (-2235 2335);
PAINT ORANGE (-2235 2335);
FORCEPROP 2 LASTPIN (-2225 2375) $PN BU72
J 2
(-2235 2385);
DISPLAY 0.617021 (-2235 2385);
PAINT ORANGE (-2235 2385);
FORCEPROP 2 LASTPIN (-2225 2425) $PN BR72
J 2
(-2235 2435);
DISPLAY 0.617021 (-2235 2435);
PAINT ORANGE (-2235 2435);
FORCEPROP 2 LASTPIN (-2225 2475) $PN G72
J 2
(-2235 2485);
DISPLAY 0.617021 (-2235 2485);
PAINT ORANGE (-2235 2485);
FORCEPROP 2 LASTPIN (-2225 2525) $PN G1
J 2
(-2235 2535);
DISPLAY 0.617021 (-2235 2535);
PAINT ORANGE (-2235 2535);
FORCEPROP 2 LASTPIN (-2225 2575) $PN E72
J 2
(-2235 2585);
DISPLAY 0.617021 (-2235 2585);
PAINT ORANGE (-2235 2585);
FORCEPROP 2 LASTPIN (-2225 2625) $PN E1
J 2
(-2235 2635);
DISPLAY 0.617021 (-2235 2635);
PAINT ORANGE (-2235 2635);
FORCEPROP 2 LASTPIN (-2225 2675) $PN C72
J 2
(-2235 2685);
DISPLAY 0.617021 (-2235 2685);
PAINT ORANGE (-2235 2685);
FORCEPROP 2 LASTPIN (-2225 2725) $PN C3
J 2
(-2235 2735);
DISPLAY 0.617021 (-2235 2735);
PAINT ORANGE (-2235 2735);
FORCEPROP 2 LASTPIN (-2225 2775) $PN BR1
J 2
(-2235 2785);
DISPLAY 0.617021 (-2235 2785);
PAINT ORANGE (-2235 2785);
FORCEPROP 2 LASTPIN (-2225 2825) $PN BU1
J 2
(-2235 2835);
DISPLAY 0.617021 (-2235 2835);
PAINT ORANGE (-2235 2835);
FORCEPROP 2 LASTPIN (-2225 2875) $PN BW1
J 2
(-2235 2885);
DISPLAY 0.617021 (-2235 2885);
PAINT ORANGE (-2235 2885);
FORCEPROP 2 LASTPIN (-2225 2925) $PN CA3
J 2
(-2235 2935);
DISPLAY 0.617021 (-2235 2935);
PAINT ORANGE (-2235 2935);
FORCEPROP 2 LASTPIN (-2225 2975) $PN A70
J 2
(-2235 2985);
DISPLAY 0.617021 (-2235 2985);
PAINT ORANGE (-2235 2985);
FORCEPROP 2 LASTPIN (-2225 3025) $PN CA5
J 2
(-2235 3035);
DISPLAY 0.617021 (-2235 3035);
PAINT ORANGE (-2235 3035);
FORCEPROP 2 LASTPIN (-2225 3075) $PN CA7
J 2
(-2235 3085);
DISPLAY 0.617021 (-2235 3085);
PAINT ORANGE (-2235 3085);
FORCEPROP 2 LASTPIN (-2225 3125) $PN CA9
J 2
(-2235 3135);
DISPLAY 0.617021 (-2235 3135);
PAINT ORANGE (-2235 3135);
FORCEPROP 2 LASTPIN (-2225 3175) $PN CA65
J 2
(-2235 3185);
DISPLAY 0.617021 (-2235 3185);
PAINT ORANGE (-2235 3185);
FORCEPROP 2 LASTPIN (-2225 3225) $PN CA66
J 2
(-2235 3235);
DISPLAY 0.617021 (-2235 3235);
PAINT ORANGE (-2235 3235);
FORCEPROP 2 LASTPIN (-2225 3275) $PN CA68
J 2
(-2235 3285);
DISPLAY 0.617021 (-2235 3285);
PAINT ORANGE (-2235 3285);
FORCEPROP 2 LASTPIN (-2225 3325) $PN BN72
J 2
(-2235 3335);
DISPLAY 0.617021 (-2235 3335);
PAINT ORANGE (-2235 3335);
FORCEPROP 2 LASTPIN (-2225 3375) $PN BN1
J 2
(-2235 3385);
DISPLAY 0.617021 (-2235 3385);
PAINT ORANGE (-2235 3385);
FORCEPROP 2 LASTPIN (-2225 3425) $PN J72
J 2
(-2235 3435);
DISPLAY 0.617021 (-2235 3435);
PAINT ORANGE (-2235 3435);
FORCEPROP 2 LASTPIN (-2225 3475) $PN J1
J 2
(-2235 3485);
DISPLAY 0.617021 (-2235 3485);
PAINT ORANGE (-2235 3485);
FORCEPROP 2 LASTPIN (-2225 3525) $PN A68
J 2
(-2235 3535);
DISPLAY 0.617021 (-2235 3535);
PAINT ORANGE (-2235 3535);
FORCEPROP 2 LASTPIN (-2225 3575) $PN A66
J 2
(-2235 3585);
DISPLAY 0.617021 (-2235 3585);
PAINT ORANGE (-2235 3585);
FORCEPROP 2 LASTPIN (-2225 3625) $PN A65
J 2
(-2235 3635);
DISPLAY 0.617021 (-2235 3635);
PAINT ORANGE (-2235 3635);
FORCEPROP 2 LASTPIN (-2225 3675) $PN A9
J 2
(-2235 3685);
DISPLAY 0.617021 (-2235 3685);
PAINT ORANGE (-2235 3685);
FORCEPROP 2 LASTPIN (-2225 3725) $PN A7
J 2
(-2235 3735);
DISPLAY 0.617021 (-2235 3735);
PAINT ORANGE (-2235 3735);
FORCEPROP 2 LASTPIN (-2225 3775) $PN A5
J 2
(-2235 3785);
DISPLAY 0.617021 (-2235 3785);
PAINT ORANGE (-2235 3785);
FORCEPROP 2 LASTPIN (-2225 3825) $PN E3
J 2
(-2235 3835);
DISPLAY 0.617021 (-2235 3835);
PAINT ORANGE (-2235 3835);
FORCEPROP 2 LASTPIN (-2225 3875) $PN F3
J 2
(-2235 3885);
DISPLAY 0.617021 (-2235 3885);
PAINT ORANGE (-2235 3885);
FORCEPROP 2 LASTPIN (-2225 3925) $PN BR3
J 2
(-2235 3935);
DISPLAY 0.617021 (-2235 3935);
PAINT ORANGE (-2235 3935);
FORCEPROP 2 LASTPIN (-2225 3975) $PN BU3
J 2
(-2235 3985);
DISPLAY 0.617021 (-2235 3985);
PAINT ORANGE (-2235 3985);
FORCEPROP 2 LASTPIN (-2225 4025) $PN E70
J 2
(-2235 4035);
DISPLAY 0.617021 (-2235 4035);
PAINT ORANGE (-2235 4035);
FORCEPROP 2 LASTPIN (-2225 4075) $PN F70
J 2
(-2235 4085);
DISPLAY 0.617021 (-2235 4085);
PAINT ORANGE (-2235 4085);
FORCEPROP 2 LASTPIN (-2225 4125) $PN BR70
J 2
(-2235 4135);
DISPLAY 0.617021 (-2235 4135);
PAINT ORANGE (-2235 4135);
FORCEPROP 2 LASTPIN (-2225 4175) $PN BU70
J 2
(-2235 4185);
DISPLAY 0.617021 (-2235 4185);
PAINT ORANGE (-2235 4185);
FORCEPROP 2 LASTPIN (-2225 4225) $PN BT69
J 2
(-2235 4235);
DISPLAY 0.617021 (-2235 4235);
PAINT ORANGE (-2235 4235);
FORCEPROP 2 LASTPIN (-2225 4275) $PN BP69
J 2
(-2235 4285);
DISPLAY 0.617021 (-2235 4285);
PAINT ORANGE (-2235 4285);
FORCEPROP 2 LASTPIN (-2225 1725) $PN A41
J 2
(-2235 1735);
DISPLAY 0.617021 (-2235 1735);
PAINT ORANGE (-2235 1735);
FORCEPROP 1 LAST PACK_TYPE BGA1
J 0
(-2175 4575);
PAINT SKYBLUE (-2175 4575);
DISPLAY INVISIBLE (-2175 4575);
FORCEPROP 2 LAST SEC_TYPE BGA1
J 0
(-2175 4575);
DISPLAY 1.021277 (-2175 4575);
PAINT ORANGE (-2175 4575);
DISPLAY INVISIBLE (-2175 4575);
FORCEPROP 2 LAST SEC 11
J 0
(-2175 4575);
DISPLAY 0.680851 (-2175 4575);
PAINT MONO (-2175 4575);
DISPLAY INVISIBLE (-2175 4575);
FORCEPROP 2 LAST CDS_LIB mstr_u_proc
J 0
(-1625 2575);
PAINT ORANGE (-1625 2575);
DISPLAY INVISIBLE (-1625 2575);
FORCEPROP 0 LAST BOM_COST SB
J 0
(-2175 4525);
DISPLAY 1.361702 (-2175 4525);
PAINT ORANGE (-2175 4525);
DISPLAY INVISIBLE (-2175 4525);
FORCEPROP 2 LAST CDS_LOCATION U7C1
J 0
(-2175 4525);
DISPLAY 0.617021 (-2175 4525);
PAINT AQUA (-2175 4525);
DISPLAY INVISIBLE (-2175 4525);
FORCEPROP 1 LAST PATH I13
J 0
(-1625 4475);
PAINT GREEN (-1625 4475);
DISPLAY INVISIBLE (-1625 4475);
FORCEPROP 0 LAST ROOM SB
J 0
(-2175 4425);
DISPLAY 1.361702 (-2175 4425);
PAINT ORANGE (-2175 4425);
DISPLAY INVISIBLE (-2175 4425);
FORCEADD GND..1
(-375 650);
FORCEPROP 3 LASTPIN (-375 700) SIG_NAME GND\g
J 0
(-365 710);
DISPLAY 0.659574 (-365 710);
PAINT MONO (-365 710);
DISPLAY INVISIBLE (-365 710);
FORCEPROP 1 LAST VOLTAGE 0.0V
J 0
(-420 607);
DISPLAY 0.340426 (-420 607);
PAINT SKYBLUE (-420 607);
DISPLAY INVISIBLE (-420 607);
FORCEPROP 2 LAST CDS_LIB mstr_symbols
J 0
(-375 650);
PAINT ORANGE (-375 650);
DISPLAY INVISIBLE (-375 650);
FORCEPROP 1 LAST SIZE 1B
J 0
(-300 600);
DISPLAY 0.872340 (-300 600);
PAINT AQUA (-300 600);
DISPLAY INVISIBLE (-300 600);
FORCEPROP 1 LAST BODY_TYPE PLUMBING
J 0
(-420 607);
DISPLAY 0.340426 (-420 607);
PAINT GREEN (-420 607);
DISPLAY INVISIBLE (-420 607);
FORCEPROP 1 LAST PATH I14
J 0
(-300 650);
DISPLAY 0.872340 (-300 650);
PAINT AQUA (-300 650);
DISPLAY INVISIBLE (-300 650);
FORCEPROP 1 LAST HDL_POWER GND
J 0
(-375 800);
DISPLAY 0.872340 (-375 800);
PAINT GREEN (-375 800);
DISPLAY INVISIBLE (-375 800);
FORCEADD GND..1
(-2800 650);
FORCEPROP 3 LASTPIN (-2800 700) SIG_NAME GND\g
J 0
(-2790 710);
DISPLAY 0.659574 (-2790 710);
PAINT MONO (-2790 710);
DISPLAY INVISIBLE (-2790 710);
FORCEPROP 1 LAST VOLTAGE 0.0V
J 0
(-2845 607);
DISPLAY 0.340426 (-2845 607);
PAINT SKYBLUE (-2845 607);
DISPLAY INVISIBLE (-2845 607);
FORCEPROP 1 LAST SIZE 1B
J 0
(-2725 600);
DISPLAY 0.872340 (-2725 600);
PAINT AQUA (-2725 600);
DISPLAY INVISIBLE (-2725 600);
FORCEPROP 2 LAST CDS_LIB mstr_symbols
J 0
(-2800 650);
PAINT ORANGE (-2800 650);
DISPLAY INVISIBLE (-2800 650);
FORCEPROP 1 LAST BODY_TYPE PLUMBING
J 0
(-2845 607);
DISPLAY 0.340426 (-2845 607);
PAINT GREEN (-2845 607);
DISPLAY INVISIBLE (-2845 607);
FORCEPROP 1 LAST PATH I15
J 0
(-2725 650);
DISPLAY 0.872340 (-2725 650);
PAINT AQUA (-2725 650);
DISPLAY INVISIBLE (-2725 650);
FORCEPROP 1 LAST HDL_POWER GND
J 0
(-2800 800);
DISPLAY 0.872340 (-2800 800);
PAINT GREEN (-2800 800);
DISPLAY INVISIBLE (-2800 800);
FORCEADD PVNN_PCH_STBY..1
(-6900 4400);
FORCEPROP 3 LASTPIN (-6900 4350) SIG_NAME PVNN_PCH_STBY\g
J 0
(-6890 4360);
DISPLAY 0.659574 (-6890 4360);
PAINT MONO (-6890 4360);
DISPLAY INVISIBLE (-6890 4360);
FORCEPROP 1 LAST VOLTAGE 1.0V
J 0
(-6945 4357);
DISPLAY 0.340426 (-6945 4357);
PAINT SKYBLUE (-6945 4357);
DISPLAY INVISIBLE (-6945 4357);
FORCEPROP 2 LAST CDS_LIB mstr_symbols
J 0
(-6900 4400);
PAINT ORANGE (-6900 4400);
DISPLAY INVISIBLE (-6900 4400);
FORCEPROP 1 LAST BODY_TYPE PLUMBING
J 0
(-6945 4357);
DISPLAY 0.340426 (-6945 4357);
PAINT GREEN (-6945 4357);
DISPLAY INVISIBLE (-6945 4357);
FORCEPROP 1 LAST PATH I20
J 0
(-6850 4425);
DISPLAY 0.872340 (-6850 4425);
PAINT AQUA (-6850 4425);
DISPLAY INVISIBLE (-6850 4425);
FORCEPROP 1 LAST HDL_POWER PVNN_PCH_STBY
J 1
(-6900 4450);
DISPLAY 0.872340 (-6900 4450);
PAINT GREEN (-6900 4450);
DISPLAY INVISIBLE (-6900 4450);
FORCEADD LBG_CORE_QAT_EXT_D..10
(-5375 2600);
FORCEPROP 1 LAST LOCATION U7C1
J 0
(-6100 4425);
DISPLAY 0.617021 (-6100 4425);
PAINT AQUA (-6100 4425);
FORCEPROP 1 LAST PART_NUMBER H91415-002
J 0
(-6425 900);
DISPLAY 0.617021 (-6425 900);
PAINT BLUE (-6425 900);
FORCEPROP 1 LAST MATERIAL IC
J 0
(-6425 4350);
DISPLAY 0.617021 (-6425 4350);
PAINT SKYBLUE (-6425 4350);
FORCEPROP 2 LASTPIN (-6475 2650) $PN AE27
J 2
(-6485 2660);
DISPLAY 0.617021 (-6485 2660);
PAINT ORANGE (-6485 2660);
FORCEPROP 2 LASTPIN (-4275 4150) $PN AK32
J 0
(-4265 4160);
DISPLAY 0.617021 (-4265 4160);
PAINT ORANGE (-4265 4160);
FORCEPROP 2 LASTPIN (-6475 4150) $PN U31
J 2
(-6485 4160);
DISPLAY 0.617021 (-6485 4160);
PAINT ORANGE (-6485 4160);
FORCEPROP 2 LASTPIN (-6475 4100) $PN U35
J 2
(-6485 4110);
DISPLAY 0.617021 (-6485 4110);
PAINT ORANGE (-6485 4110);
FORCEPROP 2 LASTPIN (-6475 4050) $PN U38
J 2
(-6485 4060);
DISPLAY 0.617021 (-6485 4060);
PAINT ORANGE (-6485 4060);
FORCEPROP 2 LASTPIN (-6475 4000) $PN V29
J 2
(-6485 4010);
DISPLAY 0.617021 (-6485 4010);
PAINT ORANGE (-6485 4010);
FORCEPROP 2 LASTPIN (-6475 3950) $PN V33
J 2
(-6485 3960);
DISPLAY 0.617021 (-6485 3960);
PAINT ORANGE (-6485 3960);
FORCEPROP 2 LASTPIN (-6475 3900) $PN V40
J 2
(-6485 3910);
DISPLAY 0.617021 (-6485 3910);
PAINT ORANGE (-6485 3910);
FORCEPROP 2 LASTPIN (-6475 3850) $PN Y29
J 2
(-6485 3860);
DISPLAY 0.617021 (-6485 3860);
PAINT ORANGE (-6485 3860);
FORCEPROP 2 LASTPIN (-6475 3800) $PN Y30
J 2
(-6485 3810);
DISPLAY 0.617021 (-6485 3810);
PAINT ORANGE (-6485 3810);
FORCEPROP 2 LASTPIN (-6475 3750) $PN Y32
J 2
(-6485 3760);
DISPLAY 0.617021 (-6485 3760);
PAINT ORANGE (-6485 3760);
FORCEPROP 2 LASTPIN (-6475 3700) $PN Y34
J 2
(-6485 3710);
DISPLAY 0.617021 (-6485 3710);
PAINT ORANGE (-6485 3710);
FORCEPROP 2 LASTPIN (-6475 3650) $PN Y36
J 2
(-6485 3660);
DISPLAY 0.617021 (-6485 3660);
PAINT ORANGE (-6485 3660);
FORCEPROP 2 LASTPIN (-6475 3600) $PN Y37
J 2
(-6485 3610);
DISPLAY 0.617021 (-6485 3610);
PAINT ORANGE (-6485 3610);
FORCEPROP 2 LASTPIN (-6475 3550) $PN Y39
J 2
(-6485 3560);
DISPLAY 0.617021 (-6485 3560);
PAINT ORANGE (-6485 3560);
FORCEPROP 2 LASTPIN (-6475 3500) $PN Y41
J 2
(-6485 3510);
DISPLAY 0.617021 (-6485 3510);
PAINT ORANGE (-6485 3510);
FORCEPROP 2 LASTPIN (-6475 3450) $PN AA29
J 2
(-6485 3460);
DISPLAY 0.617021 (-6485 3460);
PAINT ORANGE (-6485 3460);
FORCEPROP 2 LASTPIN (-6475 3400) $PN AA30
J 2
(-6485 3410);
DISPLAY 0.617021 (-6485 3410);
PAINT ORANGE (-6485 3410);
FORCEPROP 2 LASTPIN (-6475 3350) $PN AA32
J 2
(-6485 3360);
DISPLAY 0.617021 (-6485 3360);
PAINT ORANGE (-6485 3360);
FORCEPROP 2 LASTPIN (-6475 3300) $PN AA34
J 2
(-6485 3310);
DISPLAY 0.617021 (-6485 3310);
PAINT ORANGE (-6485 3310);
FORCEPROP 2 LASTPIN (-6475 3250) $PN AA36
J 2
(-6485 3260);
DISPLAY 0.617021 (-6485 3260);
PAINT ORANGE (-6485 3260);
FORCEPROP 2 LASTPIN (-6475 3200) $PN AA37
J 2
(-6485 3210);
DISPLAY 0.617021 (-6485 3210);
PAINT ORANGE (-6485 3210);
FORCEPROP 2 LASTPIN (-6475 3150) $PN AA39
J 2
(-6485 3160);
DISPLAY 0.617021 (-6485 3160);
PAINT ORANGE (-6485 3160);
FORCEPROP 2 LASTPIN (-6475 3100) $PN AA41
J 2
(-6485 3110);
DISPLAY 0.617021 (-6485 3110);
PAINT ORANGE (-6485 3110);
FORCEPROP 2 LASTPIN (-6475 3050) $PN AC29
J 2
(-6485 3060);
DISPLAY 0.617021 (-6485 3060);
PAINT ORANGE (-6485 3060);
FORCEPROP 2 LASTPIN (-6475 3000) $PN AC30
J 2
(-6485 3010);
DISPLAY 0.617021 (-6485 3010);
PAINT ORANGE (-6485 3010);
FORCEPROP 2 LASTPIN (-6475 2950) $PN AC32
J 2
(-6485 2960);
DISPLAY 0.617021 (-6485 2960);
PAINT ORANGE (-6485 2960);
FORCEPROP 2 LASTPIN (-6475 2900) $PN AC34
J 2
(-6485 2910);
DISPLAY 0.617021 (-6485 2910);
PAINT ORANGE (-6485 2910);
FORCEPROP 2 LASTPIN (-6475 2850) $PN AC36
J 2
(-6485 2860);
DISPLAY 0.617021 (-6485 2860);
PAINT ORANGE (-6485 2860);
FORCEPROP 2 LASTPIN (-6475 2800) $PN AC37
J 2
(-6485 2810);
DISPLAY 0.617021 (-6485 2810);
PAINT ORANGE (-6485 2810);
FORCEPROP 2 LASTPIN (-6475 2750) $PN AC39
J 2
(-6485 2760);
DISPLAY 0.617021 (-6485 2760);
PAINT ORANGE (-6485 2760);
FORCEPROP 2 LASTPIN (-6475 2700) $PN AC41
J 2
(-6485 2710);
DISPLAY 0.617021 (-6485 2710);
PAINT ORANGE (-6485 2710);
FORCEPROP 2 LASTPIN (-4275 4100) $PN U27
J 0
(-4265 4110);
DISPLAY 0.617021 (-4265 4110);
PAINT ORANGE (-4265 4110);
FORCEPROP 2 LASTPIN (-6475 2600) $PN AE30
J 2
(-6485 2610);
DISPLAY 0.617021 (-6485 2610);
PAINT ORANGE (-6485 2610);
FORCEPROP 2 LASTPIN (-6475 2550) $PN AE32
J 2
(-6485 2560);
DISPLAY 0.617021 (-6485 2560);
PAINT ORANGE (-6485 2560);
FORCEPROP 2 LASTPIN (-6475 2500) $PN AE34
J 2
(-6485 2510);
DISPLAY 0.617021 (-6485 2510);
PAINT ORANGE (-6485 2510);
FORCEPROP 2 LASTPIN (-6475 2450) $PN AE36
J 2
(-6485 2460);
DISPLAY 0.617021 (-6485 2460);
PAINT ORANGE (-6485 2460);
FORCEPROP 2 LASTPIN (-6475 2400) $PN AE37
J 2
(-6485 2410);
DISPLAY 0.617021 (-6485 2410);
PAINT ORANGE (-6485 2410);
FORCEPROP 2 LASTPIN (-6475 2350) $PN AE39
J 2
(-6485 2360);
DISPLAY 0.617021 (-6485 2360);
PAINT ORANGE (-6485 2360);
FORCEPROP 2 LASTPIN (-6475 2300) $PN AE41
J 2
(-6485 2310);
DISPLAY 0.617021 (-6485 2310);
PAINT ORANGE (-6485 2310);
FORCEPROP 2 LASTPIN (-6475 2250) $PN AG32
J 2
(-6485 2260);
DISPLAY 0.617021 (-6485 2260);
PAINT ORANGE (-6485 2260);
FORCEPROP 2 LASTPIN (-6475 2200) $PN AG34
J 2
(-6485 2210);
DISPLAY 0.617021 (-6485 2210);
PAINT ORANGE (-6485 2210);
FORCEPROP 2 LASTPIN (-6475 2150) $PN AG36
J 2
(-6485 2160);
DISPLAY 0.617021 (-6485 2160);
PAINT ORANGE (-6485 2160);
FORCEPROP 2 LASTPIN (-6475 2100) $PN AG37
J 2
(-6485 2110);
DISPLAY 0.617021 (-6485 2110);
PAINT ORANGE (-6485 2110);
FORCEPROP 2 LASTPIN (-6475 2050) $PN AG39
J 2
(-6485 2060);
DISPLAY 0.617021 (-6485 2060);
PAINT ORANGE (-6485 2060);
FORCEPROP 2 LASTPIN (-6475 2000) $PN AK34
J 2
(-6485 2010);
DISPLAY 0.617021 (-6485 2010);
PAINT ORANGE (-6485 2010);
FORCEPROP 2 LASTPIN (-6475 1950) $PN AK37
J 2
(-6485 1960);
DISPLAY 0.617021 (-6485 1960);
PAINT ORANGE (-6485 1960);
FORCEPROP 2 LASTPIN (-6475 1900) $PN AK39
J 2
(-6485 1910);
DISPLAY 0.617021 (-6485 1910);
PAINT ORANGE (-6485 1910);
FORCEPROP 2 LASTPIN (-6475 1850) $PN AM32
J 2
(-6485 1860);
DISPLAY 0.617021 (-6485 1860);
PAINT ORANGE (-6485 1860);
FORCEPROP 2 LASTPIN (-6475 1800) $PN AM34
J 2
(-6485 1810);
DISPLAY 0.617021 (-6485 1810);
PAINT ORANGE (-6485 1810);
FORCEPROP 2 LASTPIN (-6475 1750) $PN AM36
J 2
(-6485 1760);
DISPLAY 0.617021 (-6485 1760);
PAINT ORANGE (-6485 1760);
FORCEPROP 2 LASTPIN (-6475 1700) $PN AM37
J 2
(-6485 1710);
DISPLAY 0.617021 (-6485 1710);
PAINT ORANGE (-6485 1710);
FORCEPROP 2 LASTPIN (-6475 1650) $PN AM39
J 2
(-6485 1660);
DISPLAY 0.617021 (-6485 1660);
PAINT ORANGE (-6485 1660);
FORCEPROP 2 LASTPIN (-6475 1600) $PN AP32
J 2
(-6485 1610);
DISPLAY 0.617021 (-6485 1610);
PAINT ORANGE (-6485 1610);
FORCEPROP 2 LASTPIN (-6475 1550) $PN AP34
J 2
(-6485 1560);
DISPLAY 0.617021 (-6485 1560);
PAINT ORANGE (-6485 1560);
FORCEPROP 2 LASTPIN (-6475 1500) $PN AP36
J 2
(-6485 1510);
DISPLAY 0.617021 (-6485 1510);
PAINT ORANGE (-6485 1510);
FORCEPROP 2 LASTPIN (-6475 1450) $PN AP37
J 2
(-6485 1460);
DISPLAY 0.617021 (-6485 1460);
PAINT ORANGE (-6485 1460);
FORCEPROP 2 LASTPIN (-6475 1400) $PN AP39
J 2
(-6485 1410);
DISPLAY 0.617021 (-6485 1410);
PAINT ORANGE (-6485 1410);
FORCEPROP 2 LASTPIN (-6475 1350) $PN AT32
J 2
(-6485 1360);
DISPLAY 0.617021 (-6485 1360);
PAINT ORANGE (-6485 1360);
FORCEPROP 2 LASTPIN (-6475 1300) $PN AT34
J 2
(-6485 1310);
DISPLAY 0.617021 (-6485 1310);
PAINT ORANGE (-6485 1310);
FORCEPROP 2 LASTPIN (-6475 1250) $PN AT36
J 2
(-6485 1260);
DISPLAY 0.617021 (-6485 1260);
PAINT ORANGE (-6485 1260);
FORCEPROP 2 LASTPIN (-6475 1200) $PN AU32
J 2
(-6485 1210);
DISPLAY 0.617021 (-6485 1210);
PAINT ORANGE (-6485 1210);
FORCEPROP 2 LASTPIN (-6475 1150) $PN AU34
J 2
(-6485 1160);
DISPLAY 0.617021 (-6485 1160);
PAINT ORANGE (-6485 1160);
FORCEPROP 2 LASTPIN (-6475 1100) $PN AU36
J 2
(-6485 1110);
DISPLAY 0.617021 (-6485 1110);
PAINT ORANGE (-6485 1110);
FORCEPROP 2 LASTPIN (-4275 4050) $PN V37
J 0
(-4265 4060);
DISPLAY 0.617021 (-4265 4060);
PAINT ORANGE (-4265 4060);
FORCEPROP 2 LASTPIN (-4275 3950) $PN AK36
J 0
(-4265 3960);
DISPLAY 0.617021 (-4265 3960);
PAINT ORANGE (-4265 3960);
FORCEPROP 1 LAST PACK_TYPE BGA1
J 0
(-6425 4450);
PAINT SKYBLUE (-6425 4450);
DISPLAY INVISIBLE (-6425 4450);
FORCEPROP 2 LAST SEC_TYPE BGA1
J 0
(-6100 4475);
DISPLAY 1.021277 (-6100 4475);
PAINT ORANGE (-6100 4475);
DISPLAY INVISIBLE (-6100 4475);
FORCEPROP 2 LAST SEC 10
J 0
(-6100 4475);
DISPLAY 0.680851 (-6100 4475);
PAINT MONO (-6100 4475);
DISPLAY INVISIBLE (-6100 4475);
FORCEPROP 2 LAST CDS_LIB mstr_u_proc
J 0
(-5375 2600);
PAINT ORANGE (-5375 2600);
DISPLAY INVISIBLE (-5375 2600);
FORCEPROP 0 LAST BOM_COST SB
J 0
(-6625 4400);
DISPLAY 1.361702 (-6625 4400);
PAINT ORANGE (-6625 4400);
DISPLAY INVISIBLE (-6625 4400);
FORCEPROP 2 LAST CDS_LOCATION U7C1
J 0
(-6100 4425);
DISPLAY 0.617021 (-6100 4425);
PAINT AQUA (-6100 4425);
DISPLAY INVISIBLE (-6100 4425);
FORCEPROP 1 LAST PATH I21
J 0
(-5375 4350);
PAINT GREEN (-5375 4350);
DISPLAY INVISIBLE (-5375 4350);
FORCEPROP 0 LAST ROOM SB
J 0
(-6100 4525);
DISPLAY 1.021277 (-6100 4525);
PAINT ORANGE (-6100 4525);
DISPLAY INVISIBLE (-6100 4525);
FORCEADD OFFPAGE..2
(-3350 4050);
FORCEPROP 2 LAST $XR0 236 
J 0
(-3161 4050);
DISPLAY 0.638298 (-3161 4050);
PAINT MONO (-3161 4050);
FORCEPROP 2 LAST CDS_LIB mstr_standard
J 0
(-3350 4050);
PAINT MONO (-3350 4050);
DISPLAY INVISIBLE (-3350 4050);
FORCEPROP 1 LAST OFFPAGE TRUE
J 0
(-3025 3925);
DISPLAY 1.170213 (-3025 3925);
PAINT GREEN (-3025 3925);
DISPLAY INVISIBLE (-3025 3925);
FORCEPROP 1 LAST COMMENT_BODY TRUE
J 0
(-3395 3955);
DISPLAY 1.170213 (-3395 3955);
PAINT GREEN (-3395 3955);
DISPLAY INVISIBLE (-3395 3955);
FORCEPROP 2 LAST PATH I22
J 0
(-3175 4125);
DISPLAY 1.021277 (-3175 4125);
PAINT ORANGE (-3175 4125);
DISPLAY INVISIBLE (-3175 4125);
FORCEADD OFFPAGE..2
(-3350 3950);
FORCEPROP 2 LAST $XR0 236 
J 0
(-3161 3950);
DISPLAY 0.638298 (-3161 3950);
PAINT MONO (-3161 3950);
FORCEPROP 2 LAST CDS_LIB mstr_standard
J 0
(-3350 3950);
PAINT MONO (-3350 3950);
DISPLAY INVISIBLE (-3350 3950);
FORCEPROP 1 LAST OFFPAGE TRUE
J 0
(-3025 3825);
DISPLAY 1.170213 (-3025 3825);
PAINT GREEN (-3025 3825);
DISPLAY INVISIBLE (-3025 3825);
FORCEPROP 1 LAST COMMENT_BODY TRUE
J 0
(-3395 3855);
DISPLAY 1.170213 (-3395 3855);
PAINT GREEN (-3395 3855);
DISPLAY INVISIBLE (-3395 3855);
FORCEPROP 2 LAST PATH I23
J 0
(-3175 4025);
DISPLAY 1.021277 (-3175 4025);
PAINT ORANGE (-3175 4025);
DISPLAY INVISIBLE (-3175 4025);
FORCEADD PVNN_PCH_STBY..1
(-3850 4375);
FORCEPROP 3 LASTPIN (-3850 4325) SIG_NAME PVNN_PCH_STBY\g
J 0
(-3840 4335);
DISPLAY 0.659574 (-3840 4335);
PAINT MONO (-3840 4335);
DISPLAY INVISIBLE (-3840 4335);
FORCEPROP 1 LAST VOLTAGE 1.0V
J 0
(-3895 4332);
DISPLAY 0.340426 (-3895 4332);
PAINT SKYBLUE (-3895 4332);
DISPLAY INVISIBLE (-3895 4332);
FORCEPROP 2 LAST CDS_LIB mstr_symbols
J 0
(-3850 4375);
PAINT ORANGE (-3850 4375);
DISPLAY INVISIBLE (-3850 4375);
FORCEPROP 1 LAST BODY_TYPE PLUMBING
J 0
(-3895 4332);
DISPLAY 0.340426 (-3895 4332);
PAINT GREEN (-3895 4332);
DISPLAY INVISIBLE (-3895 4332);
FORCEPROP 1 LAST PATH I24
J 0
(-3800 4400);
DISPLAY 0.872340 (-3800 4400);
PAINT AQUA (-3800 4400);
DISPLAY INVISIBLE (-3800 4400);
FORCEPROP 1 LAST HDL_POWER PVNN_PCH_STBY
J 1
(-3850 4425);
DISPLAY 0.872340 (-3850 4425);
PAINT GREEN (-3850 4425);
DISPLAY INVISIBLE (-3850 4425);
FORCEADD P1V05_PCH_STBY..1
(-7425 2800);
FORCEPROP 3 LASTPIN (-7425 2750) SIG_NAME P1V05_PCH_STBY\g
J 0
(-7415 2760);
DISPLAY 0.659574 (-7415 2760);
PAINT MONO (-7415 2760);
DISPLAY INVISIBLE (-7415 2760);
FORCEPROP 1 LAST VOLTAGE 1.05V
J 0
(-7470 2757);
DISPLAY 0.340426 (-7470 2757);
PAINT SKYBLUE (-7470 2757);
DISPLAY INVISIBLE (-7470 2757);
FORCEPROP 2 LAST CDS_LIB mstr_symbols
J 0
(-7425 2800);
PAINT ORANGE (-7425 2800);
DISPLAY INVISIBLE (-7425 2800);
FORCEPROP 1 LAST BODY_TYPE PLUMBING
J 0
(-7470 2757);
DISPLAY 0.340426 (-7470 2757);
PAINT GREEN (-7470 2757);
DISPLAY INVISIBLE (-7470 2757);
FORCEPROP 1 LAST PATH I25
J 0
(-7375 2825);
DISPLAY 0.872340 (-7375 2825);
PAINT AQUA (-7375 2825);
DISPLAY INVISIBLE (-7375 2825);
FORCEPROP 1 LAST HDL_POWER P1V05_PCH_STBY
J 0
(-7425 2850);
DISPLAY 0.872340 (-7425 2850);
PAINT GREEN (-7425 2850);
DISPLAY INVISIBLE (-7425 2850);
FORCEADD INTEL_CORP_BPAGE..1
(0 0);
FORCEPROP 1 LAST CDS_CON_LAST_MODIFIED Tue Dec 01 11:51:58 2015
J 0
(-1425 325);
DISPLAY 1.340426 (-1425 325);
PAINT GREEN (-1425 325);
DISPLAY INVISIBLE (-1425 325);
FORCEPROP 1 LAST CUSTOM_TXT_CDS <CURRENT_DESIGN_SHEET> OF <TOTAL_DESIGN_SHEETS>
J 0
(-500 25);
PAINT GREEN (-500 25);
FORCEPROP 1 LAST CUSTOM_TXT_CDS <CON_LAST_MODIFIED>
J 0
(-1925 350);
PAINT GREEN (-1925 350);
FORCEPROP 2 LAST CUSTOM_TXT_CDS <XR_PAGE_TITLE>
J 0
(-7890 5250);
DISPLAY 0.638298 (-7890 5250);
PAINT PINK (-7890 5250);
DISPLAY INVISIBLE (-7890 5250);
FORCEPROP 1 LAST SCH_ADDRESS3 Santa Clara, CA 95052-8119
J 0
(-3975 25);
DISPLAY 0.617021 (-3975 25);
PAINT GREEN (-3975 25);
FORCEPROP 1 LAST SCH_ADDRESS2 P.O. BOX 58119
J 0
(-3975 75);
DISPLAY 0.617021 (-3975 75);
PAINT GREEN (-3975 75);
FORCEPROP 1 LAST SCH_ADDRESS1 2200 Mission College Blvd.
J 0
(-3975 125);
DISPLAY 0.617021 (-3975 125);
PAINT GREEN (-3975 125);
FORCEPROP 1 LAST SCH_TITLE LEWISBURG 10/11 PWR, GND
J 0
(-7950 50);
DISPLAY 1.212766 (-7950 50);
PAINT GREEN (-7950 50);
FORCEPROP 1 LAST SCH_NUMBER H4694802
J 0
(-1300 150);
DISPLAY 1.212766 (-1300 150);
PAINT YELLOW (-1300 150);
FORCEPROP 1 LAST SCH_DEPT BESD
J 1
(-4450 100);
DISPLAY 1.212766 (-4450 100);
PAINT YELLOW (-4450 100);
FORCEPROP 1 LAST SCH_REV 2.420
J 0
(-250 150);
DISPLAY 0.978723 (-250 150);
PAINT YELLOW (-250 150);
FORCEPROP 2 LAST CDS_LIB mstr_symbols
J 0
(0 0);
PAINT ORANGE (0 0);
DISPLAY INVISIBLE (0 0);
FORCEPROP 2 LAST PAGE_BORDER TRUE
J 0
(-7890 5250);
DISPLAY 0.851064 (-7890 5250);
PAINT PINK (-7890 5250);
DISPLAY INVISIBLE (-7890 5250);
FORCEPROP 1 LAST COMMENT_BODY TRUE
J 0
(12 12);
DISPLAY 0.638298 (12 12);
PAINT GREEN (12 12);
DISPLAY INVISIBLE (12 12);
FORCEPROP 2 LAST CDS_XR_PAGE_TITLE CR-123 : @BASEBOARD_FAB2_LIB.BASEBOARD_FAB2(SCH_1):PAGE123
J 0
(-7890 5250);
DISPLAY 0.638298 (-7890 5250);
PAINT PINK (-7890 5250);
DISPLAY INVISIBLE (-7890 5250);
WIRE 16 -1 (-1025 4275)(-375 4275);
WIRE 16 -1 (-375 4275)(-375 4225);
WIRE 16 -1 (-1025 4225)(-375 4225);
WIRE 16 -1 (-375 4225)(-375 4175);
WIRE 16 -1 (-1025 4175)(-375 4175);
WIRE 16 -1 (-375 4175)(-375 4125);
WIRE 16 -1 (-1025 4125)(-375 4125);
WIRE 16 -1 (-375 4125)(-375 4075);
WIRE 16 -1 (-375 4075)(-375 4025);
WIRE 16 -1 (-375 4075)(-1025 4075);
WIRE 16 -1 (-1025 4025)(-375 4025);
WIRE 16 -1 (-375 4025)(-375 3975);
WIRE 16 -1 (-1025 3975)(-375 3975);
WIRE 16 -1 (-375 3975)(-375 3925);
WIRE 16 -1 (-1025 3925)(-375 3925);
WIRE 16 -1 (-375 3925)(-375 3875);
WIRE 16 -1 (-1025 3875)(-375 3875);
WIRE 16 -1 (-375 3875)(-375 3825);
WIRE 16 -1 (-375 3825)(-375 3775);
WIRE 16 -1 (-375 3825)(-1025 3825);
WIRE 16 -1 (-1025 3775)(-375 3775);
WIRE 16 -1 (-375 3775)(-375 3725);
WIRE 16 -1 (-1025 3725)(-375 3725);
WIRE 16 -1 (-375 3725)(-375 3675);
WIRE 16 -1 (-1025 3675)(-375 3675);
WIRE 16 -1 (-375 3675)(-375 3625);
WIRE 16 -1 (-1025 3625)(-375 3625);
WIRE 16 -1 (-375 3625)(-375 3575);
WIRE 16 -1 (-375 3575)(-375 3525);
WIRE 16 -1 (-375 3575)(-1025 3575);
WIRE 16 -1 (-1025 3525)(-375 3525);
WIRE 16 -1 (-375 3525)(-375 3475);
WIRE 16 -1 (-1025 3475)(-375 3475);
WIRE 16 -1 (-375 3475)(-375 3425);
WIRE 16 -1 (-1025 3425)(-375 3425);
WIRE 16 -1 (-375 3425)(-375 3375);
WIRE 16 -1 (-1025 3375)(-375 3375);
WIRE 16 -1 (-375 3375)(-375 3325);
WIRE 16 -1 (-1025 3325)(-375 3325);
WIRE 16 -1 (-375 3325)(-375 3275);
WIRE 16 -1 (-1025 3275)(-375 3275);
WIRE 16 -1 (-375 3275)(-375 3225);
WIRE 16 -1 (-1025 3225)(-375 3225);
WIRE 16 -1 (-375 3225)(-375 3175);
WIRE 16 -1 (-1025 3175)(-375 3175);
WIRE 16 -1 (-375 3175)(-375 3125);
WIRE 16 -1 (-1025 3125)(-375 3125);
WIRE 16 -1 (-375 3125)(-375 3075);
WIRE 16 -1 (-1025 3075)(-375 3075);
WIRE 16 -1 (-375 3075)(-375 3025);
WIRE 16 -1 (-1025 3025)(-375 3025);
WIRE 16 -1 (-375 3025)(-375 2975);
WIRE 16 -1 (-1025 2975)(-375 2975);
WIRE 16 -1 (-375 2975)(-375 2925);
WIRE 16 -1 (-1025 2925)(-375 2925);
WIRE 16 -1 (-375 2925)(-375 2875);
WIRE 16 -1 (-1025 2875)(-375 2875);
WIRE 16 -1 (-375 2875)(-375 2825);
WIRE 16 -1 (-1025 2825)(-375 2825);
WIRE 16 -1 (-375 2825)(-375 2775);
WIRE 16 -1 (-1025 2775)(-375 2775);
WIRE 16 -1 (-375 2775)(-375 2725);
WIRE 16 -1 (-1025 2725)(-375 2725);
WIRE 16 -1 (-375 2725)(-375 2675);
WIRE 16 -1 (-1025 2675)(-375 2675);
WIRE 16 -1 (-375 2675)(-375 2625);
WIRE 16 -1 (-1025 2625)(-375 2625);
WIRE 16 -1 (-375 2625)(-375 2575);
WIRE 16 -1 (-1025 2575)(-375 2575);
WIRE 16 -1 (-375 2575)(-375 2525);
WIRE 16 -1 (-1025 2525)(-375 2525);
WIRE 16 -1 (-375 2525)(-375 2475);
WIRE 16 -1 (-1025 2475)(-375 2475);
WIRE 16 -1 (-375 2475)(-375 2425);
WIRE 16 -1 (-1025 2425)(-375 2425);
WIRE 16 -1 (-375 2425)(-375 2375);
WIRE 16 -1 (-1025 2375)(-375 2375);
WIRE 16 -1 (-375 2375)(-375 2325);
WIRE 16 -1 (-1025 2325)(-375 2325);
WIRE 16 -1 (-375 2325)(-375 2275);
WIRE 16 -1 (-1025 2275)(-375 2275);
WIRE 16 -1 (-375 2275)(-375 2225);
WIRE 16 -1 (-1025 2225)(-375 2225);
WIRE 16 -1 (-375 2225)(-375 2175);
WIRE 16 -1 (-1025 2175)(-375 2175);
WIRE 16 -1 (-375 2175)(-375 2125);
WIRE 16 -1 (-1025 2125)(-375 2125);
WIRE 16 -1 (-375 2125)(-375 2075);
WIRE 16 -1 (-1025 2075)(-375 2075);
WIRE 16 -1 (-375 2075)(-375 2025);
WIRE 16 -1 (-1025 2025)(-375 2025);
WIRE 16 -1 (-375 2025)(-375 1975);
WIRE 16 -1 (-1025 1975)(-375 1975);
WIRE 16 -1 (-375 1975)(-375 1925);
WIRE 16 -1 (-1025 1925)(-375 1925);
WIRE 16 -1 (-375 1925)(-375 1875);
WIRE 16 -1 (-375 1875)(-375 1825);
WIRE 16 -1 (-375 1875)(-1025 1875);
WIRE 16 -1 (-1025 1825)(-375 1825);
WIRE 16 -1 (-375 1825)(-375 1775);
WIRE 16 -1 (-1025 1775)(-375 1775);
WIRE 16 -1 (-375 1775)(-375 1725);
WIRE 16 -1 (-1025 1725)(-375 1725);
WIRE 16 -1 (-375 1725)(-375 1675);
WIRE 16 -1 (-1025 1675)(-375 1675);
WIRE 16 -1 (-375 1675)(-375 1625);
WIRE 16 -1 (-1025 1625)(-375 1625);
WIRE 16 -1 (-375 1625)(-375 1575);
WIRE 16 -1 (-375 1575)(-375 1525);
WIRE 16 -1 (-375 1575)(-1025 1575);
WIRE 16 -1 (-1025 1525)(-375 1525);
WIRE 16 -1 (-375 1525)(-375 1475);
WIRE 16 -1 (-1025 1475)(-375 1475);
WIRE 16 -1 (-375 1475)(-375 1425);
WIRE 16 -1 (-1025 1425)(-375 1425);
WIRE 16 -1 (-375 1425)(-375 1375);
WIRE 16 -1 (-1025 1375)(-375 1375);
WIRE 16 -1 (-375 1375)(-375 1325);
WIRE 16 -1 (-375 1325)(-375 1275);
WIRE 16 -1 (-375 1325)(-1025 1325);
WIRE 16 -1 (-1025 1275)(-375 1275);
WIRE 16 -1 (-375 1275)(-375 1225);
WIRE 16 -1 (-1025 1225)(-375 1225);
WIRE 16 -1 (-375 1225)(-375 1175);
WIRE 16 -1 (-1025 1175)(-375 1175);
WIRE 16 -1 (-375 1175)(-375 1125);
WIRE 16 -1 (-375 1125)(-375 1075);
WIRE 16 -1 (-375 1125)(-1025 1125);
WIRE 16 -1 (-1025 1075)(-375 1075);
WIRE 16 -1 (-375 1075)(-375 1025);
WIRE 16 -1 (-1025 1025)(-375 1025);
WIRE 16 -1 (-375 1025)(-375 975);
WIRE 16 -1 (-1025 975)(-375 975);
WIRE 16 -1 (-375 975)(-375 925);
WIRE 16 -1 (-375 925)(-375 875);
WIRE 16 -1 (-375 925)(-1025 925);
WIRE 16 -1 (-1025 875)(-375 875);
WIRE 16 -1 (-375 825)(-375 875);
WIRE 16 -1 (-1025 825)(-375 825);
WIRE 16 -1 (-375 700)(-375 825);
WIRE 16 -1 (-2225 4275)(-2800 4275);
WIRE 16 -1 (-2800 4275)(-2800 4225);
WIRE 16 -1 (-2800 4225)(-2225 4225);
WIRE 16 -1 (-2800 4225)(-2800 4175);
WIRE 16 -1 (-2800 4175)(-2225 4175);
WIRE 16 -1 (-2800 4175)(-2800 4125);
WIRE 16 -1 (-2225 4125)(-2800 4125);
WIRE 16 -1 (-2800 4125)(-2800 4075);
WIRE 16 -1 (-2800 4075)(-2225 4075);
WIRE 16 -1 (-2800 4075)(-2800 4025);
WIRE 16 -1 (-2225 4025)(-2800 4025);
WIRE 16 -1 (-2800 4025)(-2800 3975);
WIRE 16 -1 (-2225 3975)(-2800 3975);
WIRE 16 -1 (-2800 3975)(-2800 3925);
WIRE 16 -1 (-2225 3925)(-2800 3925);
WIRE 16 -1 (-2800 3925)(-2800 3875);
WIRE 16 -1 (-2225 3875)(-2800 3875);
WIRE 16 -1 (-2800 3875)(-2800 3825);
WIRE 16 -1 (-2225 3825)(-2800 3825);
WIRE 16 -1 (-2800 3825)(-2800 3775);
WIRE 16 -1 (-2225 3775)(-2800 3775);
WIRE 16 -1 (-2800 3775)(-2800 3725);
WIRE 16 -1 (-2225 3725)(-2800 3725);
WIRE 16 -1 (-2800 3725)(-2800 3675);
WIRE 16 -1 (-2225 3675)(-2800 3675);
WIRE 16 -1 (-2800 3675)(-2800 3625);
WIRE 16 -1 (-2225 3625)(-2800 3625);
WIRE 16 -1 (-2800 3625)(-2800 3575);
WIRE 16 -1 (-2225 3575)(-2800 3575);
WIRE 16 -1 (-2800 3575)(-2800 3525);
WIRE 16 -1 (-2800 3525)(-2225 3525);
WIRE 16 -1 (-2800 3525)(-2800 3475);
WIRE 16 -1 (-2800 3475)(-2225 3475);
WIRE 16 -1 (-2800 3475)(-2800 3425);
WIRE 16 -1 (-2225 3425)(-2800 3425);
WIRE 16 -1 (-2800 3425)(-2800 3375);
WIRE 16 -1 (-2800 3375)(-2225 3375);
WIRE 16 -1 (-2800 3375)(-2800 3325);
WIRE 16 -1 (-2800 3325)(-2225 3325);
WIRE 16 -1 (-2800 3325)(-2800 3275);
WIRE 16 -1 (-2800 3275)(-2225 3275);
WIRE 16 -1 (-2800 3275)(-2800 3225);
WIRE 16 -1 (-2800 3225)(-2225 3225);
WIRE 16 -1 (-2800 3225)(-2800 3175);
WIRE 16 -1 (-2800 3175)(-2225 3175);
WIRE 16 -1 (-2800 3175)(-2800 3125);
WIRE 16 -1 (-2800 3125)(-2225 3125);
WIRE 16 -1 (-2800 3125)(-2800 3075);
WIRE 16 -1 (-2800 3075)(-2225 3075);
WIRE 16 -1 (-2800 3075)(-2800 3025);
WIRE 16 -1 (-2800 3025)(-2225 3025);
WIRE 16 -1 (-2800 3025)(-2800 2975);
WIRE 16 -1 (-2800 2975)(-2225 2975);
WIRE 16 -1 (-2800 2975)(-2800 2925);
WIRE 16 -1 (-2800 2925)(-2225 2925);
WIRE 16 -1 (-2800 2925)(-2800 2875);
WIRE 16 -1 (-2225 2875)(-2800 2875);
WIRE 16 -1 (-2800 2875)(-2800 2825);
WIRE 16 -1 (-2800 2825)(-2225 2825);
WIRE 16 -1 (-2800 2825)(-2800 2775);
WIRE 16 -1 (-2800 2775)(-2225 2775);
WIRE 16 -1 (-2800 2775)(-2800 2725);
WIRE 16 -1 (-2225 2725)(-2800 2725);
WIRE 16 -1 (-2800 2725)(-2800 2675);
WIRE 16 -1 (-2800 2675)(-2225 2675);
WIRE 16 -1 (-2800 2675)(-2800 2625);
WIRE 16 -1 (-2800 2625)(-2225 2625);
WIRE 16 -1 (-2800 2625)(-2800 2575);
WIRE 16 -1 (-2225 2575)(-2800 2575);
WIRE 16 -1 (-2800 2575)(-2800 2525);
WIRE 16 -1 (-2225 2525)(-2800 2525);
WIRE 16 -1 (-2800 2525)(-2800 2475);
WIRE 16 -1 (-2800 2475)(-2225 2475);
WIRE 16 -1 (-2800 2475)(-2800 2425);
WIRE 16 -1 (-2800 2425)(-2225 2425);
WIRE 16 -1 (-2800 2425)(-2800 2375);
WIRE 16 -1 (-2225 2375)(-2800 2375);
WIRE 16 -1 (-2800 2375)(-2800 2325);
WIRE 16 -1 (-2800 2325)(-2225 2325);
WIRE 16 -1 (-2800 2325)(-2800 2275);
WIRE 16 -1 (-2800 2275)(-2225 2275);
WIRE 16 -1 (-2800 2275)(-2800 2225);
WIRE 16 -1 (-2800 2225)(-2225 2225);
WIRE 16 -1 (-2800 2225)(-2800 2175);
WIRE 16 -1 (-2225 2175)(-2800 2175);
WIRE 16 -1 (-2800 2175)(-2800 2125);
WIRE 16 -1 (-2800 2125)(-2225 2125);
WIRE 16 -1 (-2800 2125)(-2800 2075);
WIRE 16 -1 (-2800 2075)(-2225 2075);
WIRE 16 -1 (-2800 2075)(-2800 2025);
WIRE 16 -1 (-2800 2025)(-2225 2025);
WIRE 16 -1 (-2800 2025)(-2800 1975);
WIRE 16 -1 (-2800 1975)(-2225 1975);
WIRE 16 -1 (-2800 1975)(-2800 1925);
WIRE 16 -1 (-2800 1925)(-2225 1925);
WIRE 16 -1 (-2800 1925)(-2800 1875);
WIRE 16 -1 (-2800 1875)(-2225 1875);
WIRE 16 -1 (-2800 1875)(-2800 1825);
WIRE 16 -1 (-2225 1825)(-2800 1825);
WIRE 16 -1 (-2800 1825)(-2800 1775);
WIRE 16 -1 (-2800 1775)(-2225 1775);
WIRE 16 -1 (-2800 1775)(-2800 1725);
WIRE 16 -1 (-2800 1725)(-2225 1725);
WIRE 16 -1 (-2800 1725)(-2800 1675);
WIRE 16 -1 (-2225 1675)(-2800 1675);
WIRE 16 -1 (-2800 1675)(-2800 1625);
WIRE 16 -1 (-2225 1625)(-2800 1625);
WIRE 16 -1 (-2800 1625)(-2800 1575);
WIRE 16 -1 (-2225 1575)(-2800 1575);
WIRE 16 -1 (-2800 1575)(-2800 1525);
WIRE 16 -1 (-2225 1525)(-2800 1525);
WIRE 16 -1 (-2800 1525)(-2800 1475);
WIRE 16 -1 (-2225 1475)(-2800 1475);
WIRE 16 -1 (-2800 1475)(-2800 1425);
WIRE 16 -1 (-2225 1425)(-2800 1425);
WIRE 16 -1 (-2800 1425)(-2800 1375);
WIRE 16 -1 (-2225 1375)(-2800 1375);
WIRE 16 -1 (-2800 1375)(-2800 1325);
WIRE 16 -1 (-2225 1325)(-2800 1325);
WIRE 16 -1 (-2800 1325)(-2800 1275);
WIRE 16 -1 (-2225 1275)(-2800 1275);
WIRE 16 -1 (-2800 1275)(-2800 1225);
WIRE 16 -1 (-2225 1225)(-2800 1225);
WIRE 16 -1 (-2800 1225)(-2800 1175);
WIRE 16 -1 (-2225 1175)(-2800 1175);
WIRE 16 -1 (-2800 1175)(-2800 1125);
WIRE 16 -1 (-2225 1125)(-2800 1125);
WIRE 16 -1 (-2800 1125)(-2800 1075);
WIRE 16 -1 (-2225 1075)(-2800 1075);
WIRE 16 -1 (-2800 1075)(-2800 1025);
WIRE 16 -1 (-2225 1025)(-2800 1025);
WIRE 16 -1 (-2800 1025)(-2800 975);
WIRE 16 -1 (-2800 975)(-2225 975);
WIRE 16 -1 (-2800 975)(-2800 925);
WIRE 16 -1 (-2800 925)(-2225 925);
WIRE 16 -1 (-2800 925)(-2800 875);
WIRE 16 -1 (-2800 875)(-2225 875);
WIRE 16 -1 (-2800 875)(-2800 825);
WIRE 16 -1 (-2225 825)(-2800 825);
WIRE 16 -1 (-2800 825)(-2800 700);
WIRE 16 -1 (-6475 1100)(-6900 1100);
WIRE 16 -1 (-6900 1100)(-6900 1150);
WIRE 16 -1 (-6475 1150)(-6900 1150);
WIRE 16 -1 (-6900 1200)(-6900 1150);
WIRE 16 -1 (-6475 1200)(-6900 1200);
WIRE 16 -1 (-6900 1200)(-6900 1250);
WIRE 16 -1 (-6475 1250)(-6900 1250);
WIRE 16 -1 (-6900 1250)(-6900 1300);
WIRE 16 -1 (-6475 1300)(-6900 1300);
WIRE 16 -1 (-6900 1350)(-6900 1300);
WIRE 16 -1 (-6475 1350)(-6900 1350);
WIRE 16 -1 (-6900 1400)(-6900 1350);
WIRE 16 -1 (-6475 1400)(-6900 1400);
WIRE 16 -1 (-6900 1450)(-6900 1400);
WIRE 16 -1 (-6475 1450)(-6900 1450);
WIRE 16 -1 (-6900 1500)(-6900 1450);
WIRE 16 -1 (-6475 1500)(-6900 1500);
WIRE 16 -1 (-6900 1550)(-6900 1500);
WIRE 16 -1 (-6475 1550)(-6900 1550);
WIRE 16 -1 (-6900 1600)(-6900 1550);
WIRE 16 -1 (-6475 1600)(-6900 1600);
WIRE 16 -1 (-6900 1650)(-6900 1600);
WIRE 16 -1 (-6475 1650)(-6900 1650);
WIRE 16 -1 (-6900 1700)(-6900 1650);
WIRE 16 -1 (-6475 1700)(-6900 1700);
WIRE 16 -1 (-6900 1750)(-6900 1700);
WIRE 16 -1 (-6475 1750)(-6900 1750);
WIRE 16 -1 (-6900 1800)(-6900 1750);
WIRE 16 -1 (-6475 1800)(-6900 1800);
WIRE 16 -1 (-6900 1850)(-6900 1800);
WIRE 16 -1 (-6475 1850)(-6900 1850);
WIRE 16 -1 (-6900 1900)(-6900 1850);
WIRE 16 -1 (-6475 1900)(-6900 1900);
WIRE 16 -1 (-6900 1950)(-6900 1900);
WIRE 16 -1 (-6475 1950)(-6900 1950);
WIRE 16 -1 (-6900 2000)(-6900 1950);
WIRE 16 -1 (-6475 2000)(-6900 2000);
WIRE 16 -1 (-6900 2050)(-6900 2000);
WIRE 16 -1 (-6475 2050)(-6900 2050);
WIRE 16 -1 (-6900 2100)(-6900 2050);
WIRE 16 -1 (-6475 2100)(-6900 2100);
WIRE 16 -1 (-6900 2150)(-6900 2100);
WIRE 16 -1 (-6475 2150)(-6900 2150);
WIRE 16 -1 (-6900 2200)(-6900 2150);
WIRE 16 -1 (-6475 2200)(-6900 2200);
WIRE 16 -1 (-6900 2250)(-6900 2200);
WIRE 16 -1 (-6475 2250)(-6900 2250);
WIRE 16 -1 (-6900 2300)(-6900 2250);
WIRE 16 -1 (-6475 2300)(-6900 2300);
WIRE 16 -1 (-6900 2350)(-6900 2300);
WIRE 16 -1 (-6475 2350)(-6900 2350);
WIRE 16 -1 (-6900 2400)(-6900 2350);
WIRE 16 -1 (-6900 2400)(-6475 2400);
WIRE 16 -1 (-6900 2450)(-6900 2400);
WIRE 16 -1 (-6475 2450)(-6900 2450);
WIRE 16 -1 (-6900 2500)(-6900 2450);
WIRE 16 -1 (-6475 2500)(-6900 2500);
WIRE 16 -1 (-6900 2550)(-6900 2500);
WIRE 16 -1 (-6475 2550)(-6900 2550);
WIRE 16 -1 (-6900 2600)(-6900 2550);
WIRE 16 -1 (-6475 2600)(-6900 2600);
WIRE 16 -1 (-6900 2600)(-6900 2700);
WIRE 16 -1 (-6475 2700)(-6900 2700);
WIRE 16 -1 (-6900 2750)(-6900 2700);
WIRE 16 -1 (-6475 2750)(-6900 2750);
WIRE 16 -1 (-6900 2800)(-6900 2750);
WIRE 16 -1 (-6475 2800)(-6900 2800);
WIRE 16 -1 (-6900 2850)(-6900 2800);
WIRE 16 -1 (-6475 2850)(-6900 2850);
WIRE 16 -1 (-6900 2850)(-6900 2900);
WIRE 16 -1 (-6475 2900)(-6900 2900);
WIRE 16 -1 (-6900 2950)(-6900 2900);
WIRE 16 -1 (-6475 2950)(-6900 2950);
WIRE 16 -1 (-6900 2950)(-6900 3000);
WIRE 16 -1 (-6475 3000)(-6900 3000);
WIRE 16 -1 (-6900 3000)(-6900 3050);
WIRE 16 -1 (-6475 3050)(-6900 3050);
WIRE 16 -1 (-6900 3100)(-6900 3050);
WIRE 16 -1 (-6475 3100)(-6900 3100);
WIRE 16 -1 (-6900 3150)(-6900 3100);
WIRE 16 -1 (-6475 3150)(-6900 3150);
WIRE 16 -1 (-6900 3200)(-6900 3150);
WIRE 16 -1 (-6475 3200)(-6900 3200);
WIRE 16 -1 (-6900 3250)(-6900 3200);
WIRE 16 -1 (-6475 3250)(-6900 3250);
WIRE 16 -1 (-6900 3300)(-6900 3250);
WIRE 16 -1 (-6475 3300)(-6900 3300);
WIRE 16 -1 (-6900 3350)(-6900 3300);
WIRE 16 -1 (-6475 3350)(-6900 3350);
WIRE 16 -1 (-6900 3400)(-6900 3350);
WIRE 16 -1 (-6475 3400)(-6900 3400);
WIRE 16 -1 (-6900 3450)(-6900 3400);
WIRE 16 -1 (-6475 3450)(-6900 3450);
WIRE 16 -1 (-6900 3500)(-6900 3450);
WIRE 16 -1 (-6475 3500)(-6900 3500);
WIRE 16 -1 (-6900 3550)(-6900 3500);
WIRE 16 -1 (-6475 3550)(-6900 3550);
WIRE 16 -1 (-6900 3600)(-6900 3550);
WIRE 16 -1 (-6475 3600)(-6900 3600);
WIRE 16 -1 (-6900 3650)(-6900 3600);
WIRE 16 -1 (-6475 3650)(-6900 3650);
WIRE 16 -1 (-6900 3700)(-6900 3650);
WIRE 16 -1 (-6475 3700)(-6900 3700);
WIRE 16 -1 (-6900 3750)(-6900 3700);
WIRE 16 -1 (-6475 3750)(-6900 3750);
WIRE 16 -1 (-6900 3800)(-6900 3750);
WIRE 16 -1 (-6475 3800)(-6900 3800);
WIRE 16 -1 (-6900 3850)(-6900 3800);
WIRE 16 -1 (-6475 3850)(-6900 3850);
WIRE 16 -1 (-6900 3900)(-6900 3850);
WIRE 16 -1 (-6475 3900)(-6900 3900);
WIRE 16 -1 (-6900 3950)(-6900 3900);
WIRE 16 -1 (-6475 3950)(-6900 3950);
WIRE 16 -1 (-6900 4000)(-6900 3950);
WIRE 16 -1 (-6475 4000)(-6900 4000);
WIRE 16 -1 (-6900 4050)(-6900 4000);
WIRE 16 -1 (-6475 4050)(-6900 4050);
WIRE 16 -1 (-6900 4100)(-6900 4050);
WIRE 16 -1 (-6475 4100)(-6900 4100);
WIRE 16 -1 (-6900 4150)(-6900 4100);
WIRE 16 -1 (-6900 4150)(-6475 4150);
WIRE 16 -1 (-6900 4350)(-6900 4150);
WIRE 16 -1 (-3850 4100)(-3850 4150);
WIRE 16 -1 (-3850 4100)(-4275 4100);
WIRE 16 -1 (-3850 4150)(-3850 4325);
WIRE 16 -1 (-3850 4150)(-4275 4150);
WIRE 16 -1 (-6475 2650)(-7425 2650);
WIRE 16 -1 (-7425 2650)(-7425 2750);
WIRE 16 -1 (-3400 4050)(-4275 4050);
FORCEPROP 2 LAST SIG_NAME VSENSE_PVNN_PCH_STBY_QAT
J 0
(-4072 4061);
DISPLAY 0.617021 (-4072 4061);
PAINT ORANGE (-4072 4061);
WIRE 16 -1 (-3400 3950)(-4275 3950);
FORCEPROP 2 LAST SIG_NAME VSENSE_PVNN_PCH_STBY_FPK
J 0
(-4072 3961);
DISPLAY 0.617021 (-4072 3961);
PAINT ORANGE (-4072 3961);
DOT 1 (-375 4225);
DOT 1 (-375 4175);
DOT 1 (-375 4125);
DOT 1 (-2800 4225);
DOT 1 (-2800 4175);
DOT 1 (-2800 4125);
DOT 1 (-375 4075);
DOT 1 (-2800 4075);
DOT 1 (-375 3975);
DOT 1 (-375 4025);
DOT 1 (-375 3925);
DOT 1 (-375 3875);
DOT 1 (-375 3825);
DOT 1 (-375 3775);
DOT 1 (-375 3725);
DOT 1 (-375 3675);
DOT 1 (-375 3625);
DOT 1 (-375 3575);
DOT 1 (-375 3475);
DOT 1 (-375 3525);
DOT 1 (-375 3425);
DOT 1 (-375 3375);
DOT 1 (-375 3325);
DOT 1 (-375 3275);
DOT 1 (-375 3225);
DOT 1 (-375 3125);
DOT 1 (-375 3175);
DOT 1 (-375 3075);
DOT 1 (-375 3025);
DOT 1 (-375 2975);
DOT 1 (-375 2925);
DOT 1 (-375 2875);
DOT 1 (-375 2825);
DOT 1 (-375 2775);
DOT 1 (-375 2725);
DOT 1 (-375 2675);
DOT 1 (-375 2625);
DOT 1 (-375 2575);
DOT 1 (-375 2525);
DOT 1 (-375 2475);
DOT 1 (-375 2425);
DOT 1 (-375 2325);
DOT 1 (-375 2375);
DOT 1 (-375 2275);
DOT 1 (-375 2225);
DOT 1 (-375 2175);
DOT 1 (-375 2125);
DOT 1 (-375 2075);
DOT 1 (-375 2025);
DOT 1 (-375 1975);
DOT 1 (-375 1925);
DOT 1 (-375 1875);
DOT 1 (-375 1825);
DOT 1 (-375 1775);
DOT 1 (-375 1675);
DOT 1 (-375 1725);
DOT 1 (-375 1625);
DOT 1 (-375 1575);
DOT 1 (-375 1525);
DOT 1 (-375 1425);
DOT 1 (-375 1475);
DOT 1 (-375 1375);
DOT 1 (-375 1325);
DOT 1 (-375 1275);
DOT 1 (-375 1175);
DOT 1 (-375 1225);
DOT 1 (-375 1125);
DOT 1 (-375 1075);
DOT 1 (-375 1025);
DOT 1 (-375 975);
DOT 1 (-375 925);
DOT 1 (-375 875);
DOT 1 (-375 825);
DOT 1 (-2800 4025);
DOT 1 (-2800 3975);
DOT 1 (-2800 3925);
DOT 1 (-2800 3875);
DOT 1 (-2800 3825);
DOT 1 (-2800 3725);
DOT 1 (-2800 3775);
DOT 1 (-2800 3675);
DOT 1 (-2800 3625);
DOT 1 (-2800 3575);
DOT 1 (-2800 3475);
DOT 1 (-2800 3525);
DOT 1 (-2800 3425);
DOT 1 (-2800 3375);
DOT 1 (-2800 3325);
DOT 1 (-2800 3225);
DOT 1 (-2800 3275);
DOT 1 (-2800 3175);
DOT 1 (-2800 3125);
DOT 1 (-2800 3075);
DOT 1 (-2800 3025);
DOT 1 (-2800 2975);
DOT 1 (-2800 2925);
DOT 1 (-2800 2825);
DOT 1 (-2800 2875);
DOT 1 (-2800 2775);
DOT 1 (-2800 2725);
DOT 1 (-2800 2675);
DOT 1 (-2800 2575);
DOT 1 (-2800 2625);
DOT 1 (-2800 2525);
DOT 1 (-2800 2475);
DOT 1 (-2800 2425);
DOT 1 (-2800 2325);
DOT 1 (-2800 2375);
DOT 1 (-2800 2275);
DOT 1 (-2800 2225);
DOT 1 (-2800 2175);
DOT 1 (-2800 2125);
DOT 1 (-2800 2075);
DOT 1 (-2800 2025);
DOT 1 (-2800 1975);
DOT 1 (-2800 1925);
DOT 1 (-2800 1875);
DOT 1 (-2800 1825);
DOT 1 (-2800 1775);
DOT 1 (-2800 1675);
DOT 1 (-2800 1725);
DOT 1 (-2800 1625);
DOT 1 (-2800 1575);
DOT 1 (-2800 1525);
DOT 1 (-2800 1475);
DOT 1 (-2800 1425);
DOT 1 (-2800 1375);
DOT 1 (-2800 1325);
DOT 1 (-2800 1275);
DOT 1 (-2800 1225);
DOT 1 (-2800 1175);
DOT 1 (-2800 1125);
DOT 1 (-2800 1075);
DOT 1 (-2800 1025);
DOT 1 (-2800 975);
DOT 1 (-2800 875);
DOT 1 (-2800 825);
DOT 1 (-3850 4150);
DOT 1 (-6900 4150);
DOT 1 (-6900 4100);
DOT 1 (-6900 4050);
DOT 1 (-6900 4000);
DOT 1 (-6900 3950);
DOT 1 (-6900 3850);
DOT 1 (-6900 3900);
DOT 1 (-6900 3800);
DOT 1 (-6900 3750);
DOT 1 (-6900 3700);
DOT 1 (-6900 3650);
DOT 1 (-6900 3600);
DOT 1 (-6900 3550);
DOT 1 (-6900 3500);
DOT 1 (-6900 3450);
DOT 1 (-6900 3400);
DOT 1 (-6900 3350);
DOT 1 (-6900 3300);
DOT 1 (-6900 3250);
DOT 1 (-6900 3200);
DOT 1 (-6900 3150);
DOT 1 (-6900 3100);
DOT 1 (-6900 3050);
DOT 1 (-6900 3000);
DOT 1 (-6900 2950);
DOT 1 (-6900 2900);
DOT 1 (-6900 2850);
DOT 1 (-6900 2800);
DOT 1 (-6900 2750);
DOT 1 (-6900 2700);
DOT 1 (-6900 2550);
DOT 1 (-6900 2600);
DOT 1 (-6900 2500);
DOT 1 (-6900 2450);
DOT 1 (-6900 2400);
DOT 1 (-6900 2350);
DOT 1 (-6900 2300);
DOT 1 (-6900 2250);
DOT 1 (-6900 2200);
DOT 1 (-6900 2150);
DOT 1 (-6900 2100);
DOT 1 (-6900 2050);
DOT 1 (-6900 2000);
DOT 1 (-6900 1950);
DOT 1 (-6900 1900);
DOT 1 (-6900 1850);
DOT 1 (-6900 1800);
DOT 1 (-6900 1750);
DOT 1 (-6900 1700);
DOT 1 (-6900 1650);
DOT 1 (-6900 1600);
DOT 1 (-6900 1550);
DOT 1 (-6900 1500);
DOT 1 (-6900 1450);
DOT 1 (-6900 1400);
DOT 1 (-6900 1300);
DOT 1 (-6900 1350);
DOT 1 (-6900 1250);
DOT 1 (-6900 1200);
DOT 1 (-6900 1150);
DOT 1 (-2800 925);
FORCENOTE
ROOM=SB
(-7850 225) 0;
DISPLAY LEFT (-7850 225);
DISPLAY 1.021277 (-7850 225);
PAINT PURPLE (-7850 225);
QUIT
